FILE_TYPE=LIBRARY_PARTS;
primitive 'W25Q256','W25Q256_SMT';
  pin
    'CLK':
      PIN_NUMBER='(16)';
      INPUT_LOAD='(-0.01,0.01)';
    'CS_N':
      PIN_NUMBER='(7)';
      INPUT_LOAD='(-0.01,0.01)';
    'DI_IO'<0>:
      PIN_NUMBER='(15)';
      BIDIRECTIONAL='TRUE';
      INPUT_LOAD='(-0.01,0.01)';
      OUTPUT_LOAD='(1.0,-1.0)';
    'DO_IO'<1>:
      PIN_NUMBER='(8)';
      BIDIRECTIONAL='TRUE';
      INPUT_LOAD='(-0.01,0.01)';
      OUTPUT_LOAD='(1.0,-1.0)';
    'GND':
      PIN_NUMBER='(10)';
      PINUSE='GROUND';
      NO_LOAD_CHECK='Both';
      NO_IO_CHECK='Both';
      NO_ASSERT_CHECK='TRUE';
      NO_DIR_CHECK='TRUE';
      ALLOW_CONNECT='TRUE';
    'HOLD_N_IO'<3>:
      PIN_NUMBER='(1)';
      BIDIRECTIONAL='TRUE';
      INPUT_LOAD='(-0.01,0.01)';
      OUTPUT_LOAD='(1.0,-1.0)';
    'NC'<6>:
      PIN_NUMBER='(4)';
      PINUSE='NC';
      NO_LOAD_CHECK='Both';
      NO_IO_CHECK='Both';
      NO_ASSERT_CHECK='TRUE';
      NO_DIR_CHECK='TRUE';
      ALLOW_CONNECT='TRUE';
    'NC'<5>:
      PIN_NUMBER='(5)';
      PINUSE='NC';
      NO_LOAD_CHECK='Both';
      NO_IO_CHECK='Both';
      NO_ASSERT_CHECK='TRUE';
      NO_DIR_CHECK='TRUE';
      ALLOW_CONNECT='TRUE';
    'NC'<4>:
      PIN_NUMBER='(6)';
      PINUSE='NC';
      NO_LOAD_CHECK='Both';
      NO_IO_CHECK='Both';
      NO_ASSERT_CHECK='TRUE';
      NO_DIR_CHECK='TRUE';
      ALLOW_CONNECT='TRUE';
    'NC'<3>:
      PIN_NUMBER='(11)';
      PINUSE='NC';
      NO_LOAD_CHECK='Both';
      NO_IO_CHECK='Both';
      NO_ASSERT_CHECK='TRUE';
      NO_DIR_CHECK='TRUE';
      ALLOW_CONNECT='TRUE';
    'NC'<2>:
      PIN_NUMBER='(12)';
      PINUSE='NC';
      NO_LOAD_CHECK='Both';
      NO_IO_CHECK='Both';
      NO_ASSERT_CHECK='TRUE';
      NO_DIR_CHECK='TRUE';
      ALLOW_CONNECT='TRUE';
    'NC'<1>:
      PIN_NUMBER='(13)';
      PINUSE='NC';
      NO_LOAD_CHECK='Both';
      NO_IO_CHECK='Both';
      NO_ASSERT_CHECK='TRUE';
      NO_DIR_CHECK='TRUE';
      ALLOW_CONNECT='TRUE';
    'NC'<0>:
      PIN_NUMBER='(14)';
      PINUSE='NC';
      NO_LOAD_CHECK='Both';
      NO_IO_CHECK='Both';
      NO_ASSERT_CHECK='TRUE';
      NO_DIR_CHECK='TRUE';
      ALLOW_CONNECT='TRUE';
    'RESET_N':
      PIN_NUMBER='(3)';
      INPUT_LOAD='(-0.01,0.01)';
    'VCC':
      PIN_NUMBER='(2)';
      PINUSE='POWER';
      NO_LOAD_CHECK='Both';
      NO_IO_CHECK='Both';
      NO_ASSERT_CHECK='TRUE';
      NO_DIR_CHECK='TRUE';
      ALLOW_CONNECT='TRUE';
    'WP_N_IO'<2>:
      PIN_NUMBER='(9)';
      BIDIRECTIONAL='TRUE';
      INPUT_LOAD='(-0.01,0.01)';
      OUTPUT_LOAD='(1.0,-1.0)';
  end_pin;
  body
    PART_NAME='W25Q256';
    BODY_NAME='W25Q256';
    PHYS_DES_PREFIX='U';
  end_body;
end_primitive;

primitive 'W25Q256_XSOI';
  pin
    'WP_N_IO'<2>:
      PIN_NUMBER='(9)';
      BIDIRECTIONAL='TRUE';
      INPUT_LOAD='(-0.01,0.01)';
      OUTPUT_LOAD='(1.0,-1.0)';
    'NC'<0>:
      PIN_NUMBER='(14)';
      PINUSE='NC';
      NO_LOAD_CHECK='Both';
      NO_IO_CHECK='Both';
      NO_ASSERT_CHECK='TRUE';
      NO_DIR_CHECK='TRUE';
      ALLOW_CONNECT='TRUE';
    'NC'<1>:
      PIN_NUMBER='(13)';
      PINUSE='NC';
      NO_LOAD_CHECK='Both';
      NO_IO_CHECK='Both';
      NO_ASSERT_CHECK='TRUE';
      NO_DIR_CHECK='TRUE';
      ALLOW_CONNECT='TRUE';
    'NC'<2>:
      PIN_NUMBER='(12)';
      PINUSE='NC';
      NO_LOAD_CHECK='Both';
      NO_IO_CHECK='Both';
      NO_ASSERT_CHECK='TRUE';
      NO_DIR_CHECK='TRUE';
      ALLOW_CONNECT='TRUE';
    'NC'<3>:
      PIN_NUMBER='(11)';
      PINUSE='NC';
      NO_LOAD_CHECK='Both';
      NO_IO_CHECK='Both';
      NO_ASSERT_CHECK='TRUE';
      NO_DIR_CHECK='TRUE';
      ALLOW_CONNECT='TRUE';
    'NC'<4>:
      PIN_NUMBER='(6)';
      PINUSE='NC';
      NO_LOAD_CHECK='Both';
      NO_IO_CHECK='Both';
      NO_ASSERT_CHECK='TRUE';
      NO_DIR_CHECK='TRUE';
      ALLOW_CONNECT='TRUE';
    'NC'<5>:
      PIN_NUMBER='(5)';
      PINUSE='NC';
      NO_LOAD_CHECK='Both';
      NO_IO_CHECK='Both';
      NO_ASSERT_CHECK='TRUE';
      NO_DIR_CHECK='TRUE';
      ALLOW_CONNECT='TRUE';
    'NC'<6>:
      PIN_NUMBER='(4)';
      PINUSE='NC';
      NO_LOAD_CHECK='Both';
      NO_IO_CHECK='Both';
      NO_ASSERT_CHECK='TRUE';
      NO_DIR_CHECK='TRUE';
      ALLOW_CONNECT='TRUE';
    'GND':
      PIN_NUMBER='(10)';
      PINUSE='GROUND';
      NO_LOAD_CHECK='Both';
      NO_IO_CHECK='Both';
      NO_ASSERT_CHECK='TRUE';
      NO_DIR_CHECK='TRUE';
      ALLOW_CONNECT='TRUE';
    'DO_IO'<1>:
      PIN_NUMBER='(8)';
      BIDIRECTIONAL='TRUE';
      INPUT_LOAD='(-0.01,0.01)';
      OUTPUT_LOAD='(1.0,-1.0)';
    'CLK':
      PIN_NUMBER='(16)';
      INPUT_LOAD='(-0.01,0.01)';
    'VCC':
      PIN_NUMBER='(2)';
      PINUSE='POWER';
      NO_LOAD_CHECK='Both';
      NO_IO_CHECK='Both';
      NO_ASSERT_CHECK='TRUE';
      NO_DIR_CHECK='TRUE';
      ALLOW_CONNECT='TRUE';
    'CS_N':
      PIN_NUMBER='(7)';
      INPUT_LOAD='(-0.01,0.01)';
    'DI_IO'<0>:
      PIN_NUMBER='(15)';
      BIDIRECTIONAL='TRUE';
      INPUT_LOAD='(-0.01,0.01)';
      OUTPUT_LOAD='(1.0,-1.0)';
    'RESET_N':
      PIN_NUMBER='(3)';
      INPUT_LOAD='(-0.01,0.01)';
    'HOLD_N_IO'<3>:
      PIN_NUMBER='(1)';
      BIDIRECTIONAL='TRUE';
      INPUT_LOAD='(-0.01,0.01)';
      OUTPUT_LOAD='(1.0,-1.0)';
  end_pin;
  body
    PART_NAME='W25Q256';
    BODY_NAME='W25Q256';
    PHYS_DES_PREFIX='U';
  end_body;
end_primitive;

primitive 'W25Q256_SM';
  pin
    'DI_IO0':
      PIN_NUMBER='(5)';
      BIDIRECTIONAL='TRUE';
      INPUT_LOAD='(-0.01,0.01)';
      OUTPUT_LOAD='(1.0,-1.0)';
    'WP_N_IO2':
      PIN_NUMBER='(3)';
      BIDIRECTIONAL='TRUE';
      INPUT_LOAD='(-0.01,0.01)';
      OUTPUT_LOAD='(1.0,-1.0)';
    'DO_IO1':
      PIN_NUMBER='(2)';
      BIDIRECTIONAL='TRUE';
      INPUT_LOAD='(-0.01,0.01)';
      OUTPUT_LOAD='(1.0,-1.0)';
    'VCC':
      PIN_NUMBER='(8)';
      PINUSE='POWER';
      NO_LOAD_CHECK='Both';
      NO_IO_CHECK='Both';
      NO_ASSERT_CHECK='TRUE';
      NO_DIR_CHECK='TRUE';
      ALLOW_CONNECT='TRUE';
    'CLK':
      PIN_NUMBER='(6)';
      INPUT_LOAD='(-0.01,0.01)';
    'CS_N':
      PIN_NUMBER='(1)';
      INPUT_LOAD='(-0.01,0.01)';
    'GND':
      PIN_NUMBER='(4)';
      PINUSE='GROUND';
      NO_LOAD_CHECK='Both';
      NO_IO_CHECK='Both';
      NO_ASSERT_CHECK='TRUE';
      NO_DIR_CHECK='TRUE';
      ALLOW_CONNECT='TRUE';
    'THPAD':
      PIN_NUMBER='(9)';
      PINUSE='GROUND';
      NO_LOAD_CHECK='Both';
      NO_IO_CHECK='Both';
      NO_ASSERT_CHECK='TRUE';
      NO_DIR_CHECK='TRUE';
      ALLOW_CONNECT='TRUE';
    'HOLD_N_RESET_N_IO3':
      PIN_NUMBER='(7)';
      BIDIRECTIONAL='TRUE';
      INPUT_LOAD='(-0.01,0.01)';
      OUTPUT_LOAD='(1.0,-1.0)';
  end_pin;
  body
    PART_NAME='W25Q256';
    BODY_NAME='W25Q256';
    PHYS_DES_PREFIX='EU';
  end_body;
end_primitive;

END.
